(kicad_pcb
	(version 20260206)
	(generator "pcbnew")
	(generator_version "10.0")
	(general
		(thickness 1.6)
		(legacy_teardrops no)
	)
	(paper "A4")
	(title_block
		(title "04192023_DAF0TMB3IC0_F0TG_MB_C_brd_V02_OCP.brd")
		(comment 1 "Grand Teton / footprints 1630-1636 of 8354")
	)
	(layers
		(0 "F.Cu" signal "TOP")
		(4 "In1.Cu" signal "GND")
		(6 "In2.Cu" signal "IN1")
		(8 "In3.Cu" signal "GND1")
		(10 "In4.Cu" signal "IN2")
		(12 "In5.Cu" signal "GND2")
		(14 "In6.Cu" signal "IN3")
		(16 "In7.Cu" signal "GND3")
		(18 "In8.Cu" signal "VCC")
		(20 "In9.Cu" signal "VCC1")
		(22 "In10.Cu" signal "GND4")
		(24 "In11.Cu" signal "IN4")
		(26 "In12.Cu" signal "GND5")
		(28 "In13.Cu" signal "IN5")
		(30 "In14.Cu" signal "GND6")
		(32 "In15.Cu" signal "IN6")
		(34 "In16.Cu" signal "GND7")
		(2 "B.Cu" signal "BOTTOM")
		(9 "F.Adhes" user "F.Adhesive")
		(11 "B.Adhes" user "B.Adhesive")
		(13 "F.Paste" user "Package Geometry/Pastemask Top")
		(15 "B.Paste" user "Package Geometry/Pastemask Bottom")
		(5 "F.SilkS" user "Ref Des/Silkscreen Top")
		(7 "B.SilkS" user "Ref Des/Silkscreen Bottom")
		(1 "F.Mask" user "Board Geometry/Soldermask Top")
		(3 "B.Mask" user "Board Geometry/Soldermask Bottom")
		(17 "Dwgs.User" user "User.Drawings")
		(19 "Cmts.User" user "User.Comments")
		(21 "Eco1.User" user "User.Eco1")
		(23 "Eco2.User" user "User.Eco2")
		(25 "Edge.Cuts" user "Board Geometry/Outline")
		(27 "Margin" user)
		(31 "F.CrtYd" user "Package Geometry/Place Bound Top")
		(29 "B.CrtYd" user "Package Geometry/Place Bound Bottom")
		(35 "F.Fab" user "Ref Des/Assembly Top")
		(33 "B.Fab" user "Ref Des/Assembly Bottom")
	)
	(footprint ""
		(layer "F.Cu")
		(at 444.59652 -434.799232 90)
		(property "Reference" "R9043"
			(at 0 0 90)
			(layer "F.SilkS")
			(hide yes)
			(effects
				(font
					(size 1.27 1.27)
				)
			)
		)
		(property "Value" ""
			(at 0 0 90)
			(layer "F.Fab")
			(effects
				(font
					(size 1.27 1.27)
				)
			)
		)
		(duplicate_pad_numbers_are_jumpers no)
		(fp_line
			(start 0.7874 -0.4064)
			(end 0.7874 0.4064)
			(stroke
				(width 0.1524)
				(type default)
			)
			(layer "F.SilkS")
		)
		(fp_line
			(start -0.7874 -0.4064)
			(end 0.7874 -0.4064)
			(stroke
				(width 0.1524)
				(type default)
			)
			(layer "F.SilkS")
		)
		(fp_line
			(start 0.7874 0.4064)
			(end -0.7874 0.4064)
			(stroke
				(width 0.1524)
				(type default)
			)
			(layer "F.SilkS")
		)
		(fp_line
			(start -0.7874 0.4064)
			(end -0.7874 -0.4064)
			(stroke
				(width 0.1524)
				(type default)
			)
			(layer "F.SilkS")
		)
		(fp_line
			(start -0.12065 -0.305054)
			(end -0.12065 -0.2794)
			(stroke
				(width 0.1)
				(type default)
			)
			(layer "F.Fab")
		)
		(fp_line
			(start -0.67945 -0.305054)
			(end -0.12065 -0.305054)
			(stroke
				(width 0.1)
				(type default)
			)
			(layer "F.Fab")
		)
		(fp_line
			(start 0.67945 -0.3048)
			(end 0.67945 0.3048)
			(stroke
				(width 0.1)
				(type default)
			)
			(layer "F.Fab")
		)
		(fp_line
			(start 0.12065 -0.3048)
			(end 0.67945 -0.3048)
			(stroke
				(width 0.1)
				(type default)
			)
			(layer "F.Fab")
		)
		(fp_line
			(start 0.12065 -0.2794)
			(end 0.12065 -0.3048)
			(stroke
				(width 0.1)
				(type default)
			)
			(layer "F.Fab")
		)
		(fp_line
			(start -0.12065 -0.2794)
			(end 0.12065 -0.2794)
			(stroke
				(width 0.1)
				(type default)
			)
			(layer "F.Fab")
		)
		(fp_line
			(start 0.120396 0.2794)
			(end -0.12065 0.2794)
			(stroke
				(width 0.1)
				(type default)
			)
			(layer "F.Fab")
		)
		(fp_line
			(start -0.12065 0.2794)
			(end -0.12065 0.3048)
			(stroke
				(width 0.1)
				(type default)
			)
			(layer "F.Fab")
		)
		(fp_line
			(start 0.67945 0.3048)
			(end 0.120396 0.3048)
			(stroke
				(width 0.1)
				(type default)
			)
			(layer "F.Fab")
		)
		(fp_line
			(start 0.120396 0.3048)
			(end 0.120396 0.2794)
			(stroke
				(width 0.1)
				(type default)
			)
			(layer "F.Fab")
		)
		(fp_line
			(start -0.12065 0.3048)
			(end -0.67945 0.3048)
			(stroke
				(width 0.1)
				(type default)
			)
			(layer "F.Fab")
		)
		(fp_line
			(start -0.67945 0.3048)
			(end -0.67945 -0.305054)
			(stroke
				(width 0.1)
				(type default)
			)
			(layer "F.Fab")
		)
		(pad "1" smd circle
			(at -0.40005 0 90)
			(size 0 0)
			(layers "F.Cu" "F.Mask" "F.Paste")
			(net "P3V3_AUX")
		)
		(pad "2" smd circle
			(at 0.40005 0 90)
			(size 0 0)
			(layers "F.Cu" "F.Mask" "F.Paste")
			(net "GPU_WP_HW_CTRL_ISO")
		)
	)
	(footprint ""
		(layer "F.Cu")
		(at 150.246334 -191.371982 -90)
		(property "Reference" "R3196"
			(at 0 0 270)
			(layer "F.SilkS")
			(hide yes)
			(effects
				(font
					(size 1.27 1.27)
				)
			)
		)
		(property "Value" ""
			(at 0 0 270)
			(layer "F.Fab")
			(effects
				(font
					(size 1.27 1.27)
				)
			)
		)
		(duplicate_pad_numbers_are_jumpers no)
		(fp_line
			(start 0.440182 0.4064)
			(end -0.347218 0.4064)
			(stroke
				(width 0.1524)
				(type default)
			)
			(layer "F.SilkS")
		)
		(fp_line
			(start -0.7874 -0.020066)
			(end -0.7874 -0.4064)
			(stroke
				(width 0.1524)
				(type default)
			)
			(layer "F.SilkS")
		)
		(fp_line
			(start -0.7874 -0.4064)
			(end 0.7874 -0.4064)
			(stroke
				(width 0.1524)
				(type default)
			)
			(layer "F.SilkS")
		)
		(fp_line
			(start 0.7874 -0.4064)
			(end 0.7874 -0.020066)
			(stroke
				(width 0.1524)
				(type default)
			)
			(layer "F.SilkS")
		)
		(fp_line
			(start -0.67945 0.3048)
			(end -0.67945 -0.305054)
			(stroke
				(width 0.1)
				(type default)
			)
			(layer "F.Fab")
		)
		(fp_line
			(start -0.12065 0.3048)
			(end -0.67945 0.3048)
			(stroke
				(width 0.1)
				(type default)
			)
			(layer "F.Fab")
		)
		(fp_line
			(start 0.120396 0.3048)
			(end 0.120396 0.2794)
			(stroke
				(width 0.1)
				(type default)
			)
			(layer "F.Fab")
		)
		(fp_line
			(start 0.67945 0.3048)
			(end 0.120396 0.3048)
			(stroke
				(width 0.1)
				(type default)
			)
			(layer "F.Fab")
		)
		(fp_line
			(start -0.12065 0.2794)
			(end -0.12065 0.3048)
			(stroke
				(width 0.1)
				(type default)
			)
			(layer "F.Fab")
		)
		(fp_line
			(start 0.120396 0.2794)
			(end -0.12065 0.2794)
			(stroke
				(width 0.1)
				(type default)
			)
			(layer "F.Fab")
		)
		(fp_line
			(start -0.12065 -0.2794)
			(end 0.12065 -0.2794)
			(stroke
				(width 0.1)
				(type default)
			)
			(layer "F.Fab")
		)
		(fp_line
			(start 0.12065 -0.2794)
			(end 0.12065 -0.3048)
			(stroke
				(width 0.1)
				(type default)
			)
			(layer "F.Fab")
		)
		(fp_line
			(start 0.12065 -0.3048)
			(end 0.67945 -0.3048)
			(stroke
				(width 0.1)
				(type default)
			)
			(layer "F.Fab")
		)
		(fp_line
			(start 0.67945 -0.3048)
			(end 0.67945 0.3048)
			(stroke
				(width 0.1)
				(type default)
			)
			(layer "F.Fab")
		)
		(fp_line
			(start -0.67945 -0.305054)
			(end -0.12065 -0.305054)
			(stroke
				(width 0.1)
				(type default)
			)
			(layer "F.Fab")
		)
		(fp_line
			(start -0.12065 -0.305054)
			(end -0.12065 -0.2794)
			(stroke
				(width 0.1)
				(type default)
			)
			(layer "F.Fab")
		)
		(pad "1" smd circle
			(at -0.40005 0 270)
			(size 0 0)
			(layers "F.Cu" "F.Mask" "F.Paste")
			(net "CLK_100M_CPU1_CLK03_R_DP")
		)
		(pad "2" smd circle
			(at 0.40005 0 270)
			(size 0 0)
			(layers "F.Cu" "F.Mask" "F.Paste")
			(net "CLK_100M_CPU1_CLK03_DP")
		)
	)
	(footprint ""
		(layer "F.Cu")
		(at 426.6819 -109.644688 90)
		(property "Reference" "PC2081"
			(at 0 0 90)
			(layer "F.SilkS")
			(hide yes)
			(effects
				(font
					(size 1.27 1.27)
				)
			)
		)
		(property "Value" ""
			(at 0 0 90)
			(layer "F.Fab")
			(effects
				(font
					(size 1.27 1.27)
				)
			)
		)
		(duplicate_pad_numbers_are_jumpers no)
		(fp_line
			(start 1.524 -0.762)
			(end 1.524 0.762)
			(stroke
				(width 0.1524)
				(type default)
			)
			(layer "F.SilkS")
		)
		(fp_line
			(start -1.524 -0.762)
			(end 1.524 -0.762)
			(stroke
				(width 0.1524)
				(type default)
			)
			(layer "F.SilkS")
		)
		(fp_line
			(start 1.524 0.762)
			(end -1.524 0.762)
			(stroke
				(width 0.1524)
				(type default)
			)
			(layer "F.SilkS")
		)
		(fp_line
			(start -1.524 0.762)
			(end -1.524 -0.762)
			(stroke
				(width 0.1524)
				(type default)
			)
			(layer "F.SilkS")
		)
		(fp_line
			(start 1.1049 -0.724916)
			(end -1.1049 -0.724916)
			(stroke
				(width 0.1)
				(type default)
			)
			(layer "F.Fab")
		)
		(fp_line
			(start -1.1049 -0.724916)
			(end -1.1049 0.724916)
			(stroke
				(width 0.1)
				(type default)
			)
			(layer "F.Fab")
		)
		(fp_line
			(start 1.1049 0.724916)
			(end 1.1049 -0.724916)
			(stroke
				(width 0.1)
				(type default)
			)
			(layer "F.Fab")
		)
		(fp_line
			(start -1.1049 0.724916)
			(end 1.1049 0.724916)
			(stroke
				(width 0.1)
				(type default)
			)
			(layer "F.Fab")
		)
		(pad "1" smd rect
			(at -0.889 0 270)
			(size 1.016 1.27)
			(layers "F.Cu" "F.Mask" "F.Paste")
			(net "P3V3_OCP_SFF_R")
		)
		(pad "2" smd rect
			(at 0.889 0 270)
			(size 1.016 1.27)
			(layers "F.Cu" "F.Mask" "F.Paste")
			(net "GND")
		)
	)
	(footprint ""
		(layer "F.Cu")
		(at 204.689456 -339.428836)
		(property "Reference" "PR452"
			(at 0 0 0)
			(layer "F.SilkS")
			(hide yes)
			(effects
				(font
					(size 1.27 1.27)
				)
			)
		)
		(property "Value" ""
			(at 0 0 0)
			(layer "F.Fab")
			(effects
				(font
					(size 1.27 1.27)
				)
			)
		)
		(duplicate_pad_numbers_are_jumpers no)
		(fp_line
			(start -0.7874 -0.4064)
			(end 0.7874 -0.4064)
			(stroke
				(width 0.1524)
				(type default)
			)
			(layer "F.SilkS")
		)
		(fp_line
			(start -0.7874 0.4064)
			(end -0.7874 -0.4064)
			(stroke
				(width 0.1524)
				(type default)
			)
			(layer "F.SilkS")
		)
		(fp_line
			(start 0.7874 -0.4064)
			(end 0.7874 0.4064)
			(stroke
				(width 0.1524)
				(type default)
			)
			(layer "F.SilkS")
		)
		(fp_line
			(start 0.7874 0.4064)
			(end -0.7874 0.4064)
			(stroke
				(width 0.1524)
				(type default)
			)
			(layer "F.SilkS")
		)
		(fp_line
			(start -0.67945 -0.305054)
			(end -0.12065 -0.305054)
			(stroke
				(width 0.1)
				(type default)
			)
			(layer "F.Fab")
		)
		(fp_line
			(start -0.67945 0.3048)
			(end -0.67945 -0.305054)
			(stroke
				(width 0.1)
				(type default)
			)
			(layer "F.Fab")
		)
		(fp_line
			(start -0.12065 -0.305054)
			(end -0.12065 -0.2794)
			(stroke
				(width 0.1)
				(type default)
			)
			(layer "F.Fab")
		)
		(fp_line
			(start -0.12065 -0.2794)
			(end 0.12065 -0.2794)
			(stroke
				(width 0.1)
				(type default)
			)
			(layer "F.Fab")
		)
		(fp_line
			(start -0.12065 0.2794)
			(end -0.12065 0.3048)
			(stroke
				(width 0.1)
				(type default)
			)
			(layer "F.Fab")
		)
		(fp_line
			(start -0.12065 0.3048)
			(end -0.67945 0.3048)
			(stroke
				(width 0.1)
				(type default)
			)
			(layer "F.Fab")
		)
		(fp_line
			(start 0.120396 0.2794)
			(end -0.12065 0.2794)
			(stroke
				(width 0.1)
				(type default)
			)
			(layer "F.Fab")
		)
		(fp_line
			(start 0.120396 0.3048)
			(end 0.120396 0.2794)
			(stroke
				(width 0.1)
				(type default)
			)
			(layer "F.Fab")
		)
		(fp_line
			(start 0.12065 -0.3048)
			(end 0.67945 -0.3048)
			(stroke
				(width 0.1)
				(type default)
			)
			(layer "F.Fab")
		)
		(fp_line
			(start 0.12065 -0.2794)
			(end 0.12065 -0.3048)
			(stroke
				(width 0.1)
				(type default)
			)
			(layer "F.Fab")
		)
		(fp_line
			(start 0.67945 -0.3048)
			(end 0.67945 0.3048)
			(stroke
				(width 0.1)
				(type default)
			)
			(layer "F.Fab")
		)
		(fp_line
			(start 0.67945 0.3048)
			(end 0.120396 0.3048)
			(stroke
				(width 0.1)
				(type default)
			)
			(layer "F.Fab")
		)
		(pad "1" smd circle
			(at -0.40005 0)
			(size 0 0)
			(layers "F.Cu" "F.Mask" "F.Paste")
			(net "PVDD_33_S5_CS")
		)
		(pad "2" smd circle
			(at 0.40005 0)
			(size 0 0)
			(layers "F.Cu" "F.Mask" "F.Paste")
			(net "GND")
		)
	)
	(footprint ""
		(layer "F.Cu")
		(at 424.5356 -423.2402 90)
		(property "Reference" "R1409"
			(at 0 0 90)
			(layer "F.SilkS")
			(hide yes)
			(effects
				(font
					(size 1.27 1.27)
				)
			)
		)
		(property "Value" ""
			(at 0 0 90)
			(layer "F.Fab")
			(effects
				(font
					(size 1.27 1.27)
				)
			)
		)
		(duplicate_pad_numbers_are_jumpers no)
		(fp_line
			(start 0.32512 -0.175006)
			(end 0.32512 0.175006)
			(stroke
				(width 0.1)
				(type default)
			)
			(layer "F.Fab")
		)
		(fp_line
			(start -0.32512 -0.175006)
			(end 0.32512 -0.175006)
			(stroke
				(width 0.1)
				(type default)
			)
			(layer "F.Fab")
		)
		(fp_line
			(start 0.32512 0.175006)
			(end -0.32512 0.175006)
			(stroke
				(width 0.1)
				(type default)
			)
			(layer "F.Fab")
		)
		(fp_line
			(start -0.32512 0.175006)
			(end -0.32512 -0.175006)
			(stroke
				(width 0.1)
				(type default)
			)
			(layer "F.Fab")
		)
		(pad "1" smd rect
			(at -0.2667 0 90)
			(size 0.3048 0.381)
			(layers "F.Cu" "F.Mask" "F.Paste")
			(net "JTAG_TCK_RT_CPU0_P3")
		)
		(pad "2" smd rect
			(at 0.2667 0 270)
			(size 0.3048 0.381)
			(layers "F.Cu" "F.Mask" "F.Paste")
			(net "GND")
		)
	)
	(footprint ""
		(layer "F.Cu")
		(at 19.241516 -38.910514 180)
		(property "Reference" "R1360"
			(at 0 0 180)
			(layer "F.SilkS")
			(hide yes)
			(effects
				(font
					(size 1.27 1.27)
				)
			)
		)
		(property "Value" ""
			(at 0 0 180)
			(layer "F.Fab")
			(effects
				(font
					(size 1.27 1.27)
				)
			)
		)
		(duplicate_pad_numbers_are_jumpers no)
		(fp_line
			(start 0.7874 0.4064)
			(end -0.7874 0.4064)
			(stroke
				(width 0.1524)
				(type default)
			)
			(layer "F.SilkS")
		)
		(fp_line
			(start 0.7874 -0.4064)
			(end 0.7874 0.4064)
			(stroke
				(width 0.1524)
				(type default)
			)
			(layer "F.SilkS")
		)
		(fp_line
			(start -0.7874 0.4064)
			(end -0.7874 -0.4064)
			(stroke
				(width 0.1524)
				(type default)
			)
			(layer "F.SilkS")
		)
		(fp_line
			(start -0.7874 -0.4064)
			(end 0.7874 -0.4064)
			(stroke
				(width 0.1524)
				(type default)
			)
			(layer "F.SilkS")
		)
		(fp_line
			(start 0.67945 0.3048)
			(end 0.120396 0.3048)
			(stroke
				(width 0.1)
				(type default)
			)
			(layer "F.Fab")
		)
		(fp_line
			(start 0.67945 -0.3048)
			(end 0.67945 0.3048)
			(stroke
				(width 0.1)
				(type default)
			)
			(layer "F.Fab")
		)
		(fp_line
			(start 0.12065 -0.2794)
			(end 0.12065 -0.3048)
			(stroke
				(width 0.1)
				(type default)
			)
			(layer "F.Fab")
		)
		(fp_line
			(start 0.12065 -0.3048)
			(end 0.67945 -0.3048)
			(stroke
				(width 0.1)
				(type default)
			)
			(layer "F.Fab")
		)
		(fp_line
			(start 0.120396 0.3048)
			(end 0.120396 0.2794)
			(stroke
				(width 0.1)
				(type default)
			)
			(layer "F.Fab")
		)
		(fp_line
			(start 0.120396 0.2794)
			(end -0.12065 0.2794)
			(stroke
				(width 0.1)
				(type default)
			)
			(layer "F.Fab")
		)
		(fp_line
			(start -0.12065 0.3048)
			(end -0.67945 0.3048)
			(stroke
				(width 0.1)
				(type default)
			)
			(layer "F.Fab")
		)
		(fp_line
			(start -0.12065 0.2794)
			(end -0.12065 0.3048)
			(stroke
				(width 0.1)
				(type default)
			)
			(layer "F.Fab")
		)
		(fp_line
			(start -0.12065 -0.2794)
			(end 0.12065 -0.2794)
			(stroke
				(width 0.1)
				(type default)
			)
			(layer "F.Fab")
		)
		(fp_line
			(start -0.12065 -0.305054)
			(end -0.12065 -0.2794)
			(stroke
				(width 0.1)
				(type default)
			)
			(layer "F.Fab")
		)
		(fp_line
			(start -0.67945 0.3048)
			(end -0.67945 -0.305054)
			(stroke
				(width 0.1)
				(type default)
			)
			(layer "F.Fab")
		)
		(fp_line
			(start -0.67945 -0.305054)
			(end -0.12065 -0.305054)
			(stroke
				(width 0.1)
				(type default)
			)
			(layer "F.Fab")
		)
		(pad "1" smd circle
			(at -0.40005 0 180)
			(size 0 0)
			(layers "F.Cu" "F.Mask" "F.Paste")
			(net "INA230_7_A0")
		)
		(pad "2" smd circle
			(at 0.40005 0 180)
			(size 0 0)
			(layers "F.Cu" "F.Mask" "F.Paste")
			(net "SMB_INA230_7_3V3AUX_SCL_R1")
		)
	)
	(footprint ""
		(layer "F.Cu")
		(at 200.939908 -107.529376 180)
		(property "Reference" "R208"
			(at 0 0 180)
			(layer "F.SilkS")
			(hide yes)
			(effects
				(font
					(size 1.27 1.27)
				)
			)
		)
		(property "Value" ""
			(at 0 0 180)
			(layer "F.Fab")
			(effects
				(font
					(size 1.27 1.27)
				)
			)
		)
		(duplicate_pad_numbers_are_jumpers no)
		(fp_line
			(start 0.7874 0.4064)
			(end -0.7874 0.4064)
			(stroke
				(width 0.1524)
				(type default)
			)
			(layer "F.SilkS")
		)
		(fp_line
			(start 0.7874 -0.4064)
			(end 0.7874 0.4064)
			(stroke
				(width 0.1524)
				(type default)
			)
			(layer "F.SilkS")
		)
		(fp_line
			(start -0.7874 0.4064)
			(end -0.7874 -0.4064)
			(stroke
				(width 0.1524)
				(type default)
			)
			(layer "F.SilkS")
		)
		(fp_line
			(start -0.7874 -0.4064)
			(end 0.7874 -0.4064)
			(stroke
				(width 0.1524)
				(type default)
			)
			(layer "F.SilkS")
		)
		(fp_line
			(start 0.67945 0.3048)
			(end 0.120396 0.3048)
			(stroke
				(width 0.1)
				(type default)
			)
			(layer "F.Fab")
		)
		(fp_line
			(start 0.67945 -0.3048)
			(end 0.67945 0.3048)
			(stroke
				(width 0.1)
				(type default)
			)
			(layer "F.Fab")
		)
		(fp_line
			(start 0.12065 -0.2794)
			(end 0.12065 -0.3048)
			(stroke
				(width 0.1)
				(type default)
			)
			(layer "F.Fab")
		)
		(fp_line
			(start 0.12065 -0.3048)
			(end 0.67945 -0.3048)
			(stroke
				(width 0.1)
				(type default)
			)
			(layer "F.Fab")
		)
		(fp_line
			(start 0.120396 0.3048)
			(end 0.120396 0.2794)
			(stroke
				(width 0.1)
				(type default)
			)
			(layer "F.Fab")
		)
		(fp_line
			(start 0.120396 0.2794)
			(end -0.12065 0.2794)
			(stroke
				(width 0.1)
				(type default)
			)
			(layer "F.Fab")
		)
		(fp_line
			(start -0.12065 0.3048)
			(end -0.67945 0.3048)
			(stroke
				(width 0.1)
				(type default)
			)
			(layer "F.Fab")
		)
		(fp_line
			(start -0.12065 0.2794)
			(end -0.12065 0.3048)
			(stroke
				(width 0.1)
				(type default)
			)
			(layer "F.Fab")
		)
		(fp_line
			(start -0.12065 -0.2794)
			(end 0.12065 -0.2794)
			(stroke
				(width 0.1)
				(type default)
			)
			(layer "F.Fab")
		)
		(fp_line
			(start -0.12065 -0.305054)
			(end -0.12065 -0.2794)
			(stroke
				(width 0.1)
				(type default)
			)
			(layer "F.Fab")
		)
		(fp_line
			(start -0.67945 0.3048)
			(end -0.67945 -0.305054)
			(stroke
				(width 0.1)
				(type default)
			)
			(layer "F.Fab")
		)
		(fp_line
			(start -0.67945 -0.305054)
			(end -0.12065 -0.305054)
			(stroke
				(width 0.1)
				(type default)
			)
			(layer "F.Fab")
		)
		(pad "1" smd circle
			(at -0.40005 0 180)
			(size 0 0)
			(layers "F.Cu" "F.Mask" "F.Paste")
			(net "PVDDCR_CPU0_P1_EN")
		)
		(pad "2" smd circle
			(at 0.40005 0 180)
			(size 0 0)
			(layers "F.Cu" "F.Mask" "F.Paste")
			(net "FM_PVDDCR_CPU0_P1_R_EN")
		)
	)
)
